# BASEBOARD_FAB2 (Tioga Pass) — schematic netlist excerpt (pin names and nets, part order shuffled) for the footprints in the layout excerpt that follows; sources: Cadence DE-HDL packaged netlist, KiCad conversion of Wiwynn_Tioga_Pass_MB.brd

J4G2  SCONN288_H44441004  SCONN  pkg PIP  page 45
  \12v\(1)  = P12V_NVDIMM_ABC
  VSS(93)  = GND
  DQ(4)  = M_B_DQ<5>
  VSS(92)  = GND
  DQ(0)  = M_B_DQ<1>
  VSS(91)  = GND
  DQS9P  = M_B_DQS_DP<9>
  DQS9N  = M_B_DQS_DN<9>
  VSS(90)  = GND
  DQ(6)  = M_B_DQ<7>
  VSS(89)  = GND
  DQ(2)  = M_B_DQ<3>
  VSS(88)  = GND
  DQ(12)  = M_B_DQ<13>
  VSS(87)  = GND
  DQ(8)  = M_B_DQ<9>
  VSS(86)  = GND
  DQS10P  = M_B_DQS_DP<10>
  DQS10N  = M_B_DQS_DN<10>
  VSS(85)  = GND
  DQ(14)  = M_B_DQ<15>
  VSS(84)  = GND
  DQ(10)  = M_B_DQ<11>
  VSS(83)  = GND
  DQ(20)  = M_B_DQ<21>
  VSS(82)  = GND
  DQ(16)  = M_B_DQ<17>
  VSS(81)  = GND
  DQS11P  = M_B_DQS_DP<11>
  DQS11N  = M_B_DQS_DN<11>
  VSS(80)  = GND
  DQ(22)  = M_B_DQ<23>
  VSS(79)  = GND
  DQ(18)  = M_B_DQ<19>
  VSS(78)  = GND
  DQ(28)  = M_B_DQ<29>
  VSS(77)  = GND
  DQ(24)  = M_B_DQ<25>
  VSS(76)  = GND
  DQS12P  = M_B_DQS_DP<12>
  DQS12N  = M_B_DQS_DN<12>
  VSS(75)  = GND
  DQ(30)  = M_B_DQ<31>
  VSS(74)  = GND
  DQ(26)  = M_B_DQ<27>
  VSS(73)  = GND
  CB(4)  = M_B_ECC<5>
  VSS(72)  = GND
  CB(0)  = M_B_ECC<1>
  VSS(71)  = GND
  DQS17P  = M_B_DQS_DP<17>
  DQS17N  = M_B_DQS_DN<17>
  VSS(70)  = GND
  CB(6)  = M_B_ECC<7>
  VSS(69)  = GND
  CB(2)  = M_B_ECC<3>
  VSS(68)  = GND
  RESET_N  = M_ABC_RST_N
  VDD(25)  = PVDDQ_ABC
  CKE(0)  = M_B_CKE<0>
  VDD(24)  = PVDDQ_ABC
  ACT_N  = M_B_ACT_N
  BG(0)  = M_B_BG<0>
  VDD(23)  = PVDDQ_ABC
  A12  = M_B_MA<12>
  A9  = M_B_MA<9>
  VDD(22)  = PVDDQ_ABC
  A8  = M_B_MA<8>
  A6  = M_B_MA<6>
  VDD(21)  = PVDDQ_ABC
  A3  = M_B_MA<3>
  A1  = M_B_MA<1>
  VDD(20)  = PVDDQ_ABC
  CK0P  = M_B_CLK_DP<0>
  CK0N  = M_B_CLK_DN<0>
  VDD(19)  = PVDDQ_ABC
  VTT(1)  = PVTT_ABC
  EVENT_N  = FM_DIMM_EVENT_COD_N
  A0  = M_B_MA<0>
  VDD(18)  = PVDDQ_ABC
  BA(0)  = M_B_BA<0>
  A16_RAS_N  = M_B_MA<16>
  VDD(17)  = PVDDQ_ABC
  S0_N  = M_B_CS_N<0>
  VDD(16)  = PVDDQ_ABC
  A15_CAS_N  = M_B_MA<15>
  ODT(0)  = M_B_ODT<0>
  VDD(15)  = PVDDQ_ABC
  S1_N  = M_B_CS_N<1>
  VDD(14)  = PVDDQ_ABC
  ODT(1)  = M_B_ODT<1>
  VDD(13)  = PVDDQ_ABC
  S2_N_C(0)  = M_B_CS_N<2>
  VSS(67)  = GND
  DQ(36)  = M_B_DQ<37>
  VSS(66)  = GND
  DQ(32)  = M_B_DQ<33>
  VSS(65)  = GND
  DQS13P  = M_B_DQS_DP<13>
  DQS13N  = M_B_DQS_DN<13>
  VSS(64)  = GND
  DQ(38)  = M_B_DQ<39>
  VSS(63)  = GND
  DQ(34)  = M_B_DQ<35>
  VSS(62)  = GND
  DQ(44)  = M_B_DQ<45>
  VSS(61)  = GND
  DQ(40)  = M_B_DQ<41>
  VSS(60)  = GND
  DQS14P  = M_B_DQS_DP<14>
  DQS14N  = M_B_DQS_DN<14>
  VSS(59)  = GND
  DQ(46)  = M_B_DQ<47>
  VSS(58)  = GND
  DQ(42)  = M_B_DQ<43>
  VSS(57)  = GND
  DQ(52)  = M_B_DQ<53>
  VSS(56)  = GND
  DQ(48)  = M_B_DQ<49>
  VSS(55)  = GND
  DQS15P  = M_B_DQS_DP<15>
  DQS15N  = M_B_DQS_DN<15>
  VSS(54)  = GND
  DQ(54)  = M_B_DQ<55>
  VSS(53)  = GND
  DQ(50)  = M_B_DQ<51>
  VSS(52)  = GND
  DQ(60)  = M_B_DQ<61>
  VSS(51)  = GND
  DQ(56)  = M_B_DQ<57>
  VSS(50)  = GND
  DQS16P  = M_B_DQS_DP<16>
  DQS16N  = M_B_DQS_DN<16>
  VSS(49)  = GND
  DQ(62)  = M_B_DQ<63>
  VSS(48)  = GND
  DQ(58)  = M_B_DQ<59>
  VSS(47)  = GND
  SA(0)  = GND
  SA(1)  = PVPP_ABC
  SCL  = SMB_DDR_ABC_VPP_SCL
  VPP(4)  = PVPP_ABC
  VPP(3)  = PVPP_ABC
  RFU(2)  = TP_CH_B_DIMM_B0_RFU_2
  \12v\(0)  = P12V_NVDIMM_ABC
  VREFCA  = M_B_VREF
  VSS(46)  = GND
  DQ(5)  = M_B_DQ<4>
  VSS(45)  = GND
  DQ(1)  = M_B_DQ<0>
  VSS(44)  = GND
  DQS0N  = M_B_DQS_DN<0>
  DQS0P  = M_B_DQS_DP<0>
  VSS(43)  = GND
  DQ(7)  = M_B_DQ<6>
  VSS(42)  = GND
  DQ(3)  = M_B_DQ<2>
  VSS(41)  = GND
  DQ(13)  = M_B_DQ<12>
  VSS(40)  = GND
  DQ(9)  = M_B_DQ<8>
  VSS(39)  = GND
  DQS1N  = M_B_DQS_DN<1>
  DQS1P  = M_B_DQS_DP<1>
  VSS(38)  = GND
  DQ(15)  = M_B_DQ<14>
  VSS(37)  = GND
  DQ(11)  = M_B_DQ<10>
  VSS(36)  = GND
  DQ(21)  = M_B_DQ<20>
  VSS(35)  = GND
  DQ(17)  = M_B_DQ<16>
  VSS(34)  = GND
  DQS2N  = M_B_DQS_DN<2>
  DQS2P  = M_B_DQS_DP<2>
  VSS(33)  = GND
  DQ(23)  = M_B_DQ<22>
  VSS(32)  = GND
  DQ(19)  = M_B_DQ<18>
  VSS(31)  = GND
  DQ(29)  = M_B_DQ<28>
  VSS(30)  = GND
  DQ(25)  = M_B_DQ<24>
  VSS(29)  = GND
  DQS3N  = M_B_DQS_DN<3>
  DQS3P  = M_B_DQS_DP<3>
  VSS(28)  = GND
  DQ(31)  = M_B_DQ<30>
  VSS(27)  = GND
  DQ(27)  = M_B_DQ<26>
  VSS(26)  = GND
  CB(5)  = M_B_ECC<4>
  VSS(25)  = GND
  CB(1)  = M_B_ECC<0>
  VSS(24)  = GND
  DQS8N  = M_B_DQS_DN<8>
  DQS8P  = M_B_DQS_DP<8>
  VSS(23)  = GND
  CB(7)  = M_B_ECC<6>
  VSS(22)  = GND
  CB(3)  = M_B_ECC<2>
  VSS(21)  = GND
  CKE(1)  = M_B_CKE<1>
  VDD(12)  = PVDDQ_ABC
  RFU(0)  = TP_CH_B_DIMM_B0_RFU_0
  VDD(11)  = PVDDQ_ABC
  BG(1)  = M_B_BG<1>
  ALERT_N  = M_B_ALERT_N
  VDD(10)  = PVDDQ_ABC
  A11  = M_B_MA<11>
  A7  = M_B_MA<7>
  VDD(9)  = PVDDQ_ABC
  A5  = M_B_MA<5>
  A4  = M_B_MA<4>
  VDD(8)  = PVDDQ_ABC
  A2  = M_B_MA<2>
  VDD(7)  = PVDDQ_ABC
  CK1P  = M_B_CLK_DP<1>
  CK1N  = M_B_CLK_DN<1>
  VDD(6)  = PVDDQ_ABC
  VTT(0)  = PVTT_ABC
  PAR  = M_B_PAR
  VDD(5)  = PVDDQ_ABC
  BA(1)  = M_B_BA<1>
  A10  = M_B_MA<10>
  VDD(4)  = PVDDQ_ABC
  RFU(1)  = TP_CH_B_DIMM_B0_RFU_1
  A14_WE_N  = M_B_MA<14>
  VDD(3)  = PVDDQ_ABC
  SAVE_N_NC  = FM_ADR_COMPLETE_ABC_N
  VDD(2)  = PVDDQ_ABC
  A13  = M_B_MA<13>
  VDD(1)  = PVDDQ_ABC
  A17  = M_B_MA<17>
  C(2)  = M_B_C<2>
  VDD(0)  = PVDDQ_ABC
  S3_N_C(1)  = M_B_CS_N<3>
  SA(2)  = GND
  VSS(20)  = GND
  DQ(37)  = M_B_DQ<36>
  VSS(19)  = GND
  DQ(33)  = M_B_DQ<32>
  VSS(18)  = GND
  DQS4N  = M_B_DQS_DN<4>
  DQS4P  = M_B_DQS_DP<4>
  VSS(17)  = GND
  DQ(39)  = M_B_DQ<38>
  VSS(16)  = GND
  DQ(35)  = M_B_DQ<34>
  VSS(15)  = GND
  DQ(45)  = M_B_DQ<44>
  VSS(14)  = GND
  DQ(41)  = M_B_DQ<40>
  VSS(13)  = GND
  DQS5N  = M_B_DQS_DN<5>
  DQS5P  = M_B_DQS_DP<5>
  VSS(12)  = GND
  DQ(47)  = M_B_DQ<46>
  VSS(11)  = GND
  DQ(43)  = M_B_DQ<42>
  VSS(10)  = GND
  DQ(53)  = M_B_DQ<52>
  VSS(9)  = GND
  DQ(49)  = M_B_DQ<48>
  VSS(8)  = GND
  DQS6N  = M_B_DQS_DN<6>
  DQS6P  = M_B_DQS_DP<6>
  VSS(7)  = GND
  DQ(55)  = M_B_DQ<54>
  VSS(6)  = GND
  DQ(51)  = M_B_DQ<50>
  VSS(5)  = GND
  DQ(61)  = M_B_DQ<60>
  VSS(4)  = GND
  DQ(57)  = M_B_DQ<56>
  VSS(3)  = GND
  DQS7N  = M_B_DQS_DN<7>
  DQS7P  = M_B_DQS_DP<7>
  VSS(2)  = GND
  DQ(63)  = M_B_DQ<62>
  VSS(1)  = GND
  DQ(59)  = M_B_DQ<58>
  VSS(0)  = GND
  VDDSPD  = PVPP_ABC
  SDA  = SMB_DDR_ABC_VPP_SDA
  VPP(1)  = PVPP_ABC
  VPP(0)  = PVPP_ABC
  VPP(2)  = PVPP_ABC

(kicad_pcb
	(version 20260206)
	(generator "pcbnew")
	(generator_version "10.0")
	(general
		(thickness 1.6)
		(legacy_teardrops no)
	)
	(paper "A4")
	(title_block
		(title "Wiwynn_Tioga_Pass_MB.brd")
		(comment 1 "Tioga Pass / footprint 1899 of 4770 (J4G2), pads 153-202 of 291")
	)
	(layers
		(0 "F.Cu" signal "TOP")
		(4 "In1.Cu" signal "L2GND")
		(6 "In2.Cu" signal "L3")
		(8 "In3.Cu" signal "L4GND")
		(10 "In4.Cu" signal "L5")
		(12 "In5.Cu" signal "L6GND")
		(14 "In6.Cu" signal "L7VCC")
		(16 "In7.Cu" signal "L8VCC")
		(18 "In8.Cu" signal "L9GND")
		(20 "In9.Cu" signal "L10")
		(22 "In10.Cu" signal "L11GND")
		(24 "In11.Cu" signal "L12")
		(26 "In12.Cu" signal "L13GND")
		(2 "B.Cu" signal "BOTTOM")
		(9 "F.Adhes" user "F.Adhesive")
		(11 "B.Adhes" user "B.Adhesive")
		(13 "F.Paste" user "Package Geometry/Pastemask Top")
		(15 "B.Paste" user "Package Geometry/Pastemask Bottom")
		(5 "F.SilkS" user "Ref Des/Silkscreen Top")
		(7 "B.SilkS" user "Ref Des/Silkscreen Bottom")
		(1 "F.Mask" user "Board Geometry/Soldermask Top")
		(3 "B.Mask" user "Board Geometry/Soldermask Bottom")
		(17 "Dwgs.User" user "User.Drawings")
		(19 "Cmts.User" user "User.Comments")
		(21 "Eco1.User" user "User.Eco1")
		(23 "Eco2.User" user "User.Eco2")
		(25 "Edge.Cuts" user "Board Geometry/Outline")
		(27 "Margin" user)
		(31 "F.CrtYd" user "Package Geometry/Place Bound Top")
		(29 "B.CrtYd" user "Package Geometry/Place Bound Bottom")
		(35 "F.Fab" user "Ref Des/Assembly Top")
		(33 "B.Fab" user "Ref Des/Assembly Bottom")
	)
	(footprint ""
		(layer "F.Cu")
		(at 194.700398 -5.822442 90)
		(property "Reference" "J4G2"
			(at 6.596888 37.58311 0)
			(unlocked yes)
			(layer "F.SilkS")
			(effects
				(font
					(size 0.7874 0.5842)
					(thickness 0.1524)
				)
				(justify left)
			)
		)
		(property "Value" ""
			(at 0 0 90)
			(layer "F.Fab")
			(effects
				(font
					(size 1.27 1.27)
				)
			)
		)
		(duplicate_pad_numbers_are_jumpers no)
		(pad "150" smd rect
			(at 4.59994 4.249928 90)
			(size 1.8034 0.508)
			(layers "F.Cu" "F.Mask" "F.Paste")
			(net "M_B_DQ<0>")
		)
		(pad "151" smd rect
			(at 4.59994 5.100066 90)
			(size 1.8034 0.508)
			(layers "F.Cu" "F.Mask" "F.Paste")
			(net "GND")
		)
		(pad "152" smd rect
			(at 4.59994 5.94995 90)
			(size 1.8034 0.508)
			(layers "F.Cu" "F.Mask" "F.Paste")
			(net "M_B_DQS_DN<0>")
		)
		(pad "153" smd rect
			(at 4.59994 6.800088 90)
			(size 1.8034 0.508)
			(layers "F.Cu" "F.Mask" "F.Paste")
			(net "M_B_DQS_DP<0>")
		)
		(pad "154" smd rect
			(at 4.59994 7.649972 90)
			(size 1.8034 0.508)
			(layers "F.Cu" "F.Mask" "F.Paste")
			(net "GND")
		)
		(pad "155" smd rect
			(at 4.59994 8.50011 90)
			(size 1.8034 0.508)
			(layers "F.Cu" "F.Mask" "F.Paste")
			(net "M_B_DQ<6>")
		)
		(pad "156" smd rect
			(at 4.59994 9.349994 90)
			(size 1.8034 0.508)
			(layers "F.Cu" "F.Mask" "F.Paste")
			(net "GND")
		)
		(pad "157" smd rect
			(at 4.59994 10.199878 90)
			(size 1.8034 0.508)
			(layers "F.Cu" "F.Mask" "F.Paste")
			(net "M_B_DQ<2>")
		)
		(pad "158" smd rect
			(at 4.59994 11.050016 90)
			(size 1.8034 0.508)
			(layers "F.Cu" "F.Mask" "F.Paste")
			(net "GND")
		)
		(pad "159" smd rect
			(at 4.59994 11.8999 90)
			(size 1.8034 0.508)
			(layers "F.Cu" "F.Mask" "F.Paste")
			(net "M_B_DQ<12>")
		)
		(pad "160" smd rect
			(at 4.59994 12.750038 90)
			(size 1.8034 0.508)
			(layers "F.Cu" "F.Mask" "F.Paste")
			(net "GND")
		)
		(pad "161" smd rect
			(at 4.59994 13.599922 90)
			(size 1.8034 0.508)
			(layers "F.Cu" "F.Mask" "F.Paste")
			(net "M_B_DQ<8>")
		)
		(pad "162" smd rect
			(at 4.59994 14.45006 90)
			(size 1.8034 0.508)
			(layers "F.Cu" "F.Mask" "F.Paste")
			(net "GND")
		)
		(pad "163" smd rect
			(at 4.59994 15.299944 90)
			(size 1.8034 0.508)
			(layers "F.Cu" "F.Mask" "F.Paste")
			(net "M_B_DQS_DN<1>")
		)
		(pad "164" smd rect
			(at 4.59994 16.150082 90)
			(size 1.8034 0.508)
			(layers "F.Cu" "F.Mask" "F.Paste")
			(net "M_B_DQS_DP<1>")
		)
		(pad "165" smd rect
			(at 4.59994 16.999966 90)
			(size 1.8034 0.508)
			(layers "F.Cu" "F.Mask" "F.Paste")
			(net "GND")
		)
		(pad "166" smd rect
			(at 4.59994 17.850104 90)
			(size 1.8034 0.508)
			(layers "F.Cu" "F.Mask" "F.Paste")
			(net "M_B_DQ<14>")
		)
		(pad "167" smd rect
			(at 4.59994 18.699988 90)
			(size 1.8034 0.508)
			(layers "F.Cu" "F.Mask" "F.Paste")
			(net "GND")
		)
		(pad "168" smd rect
			(at 4.59994 19.550126 90)
			(size 1.8034 0.508)
			(layers "F.Cu" "F.Mask" "F.Paste")
			(net "M_B_DQ<10>")
		)
		(pad "169" smd rect
			(at 4.59994 20.40001 90)
			(size 1.8034 0.508)
			(layers "F.Cu" "F.Mask" "F.Paste")
			(net "GND")
		)
		(pad "170" smd rect
			(at 4.59994 21.249894 90)
			(size 1.8034 0.508)
			(layers "F.Cu" "F.Mask" "F.Paste")
			(net "M_B_DQ<20>")
		)
		(pad "171" smd rect
			(at 4.59994 22.100032 90)
			(size 1.8034 0.508)
			(layers "F.Cu" "F.Mask" "F.Paste")
			(net "GND")
		)
		(pad "172" smd rect
			(at 4.59994 22.949916 90)
			(size 1.8034 0.508)
			(layers "F.Cu" "F.Mask" "F.Paste")
			(net "M_B_DQ<16>")
		)
		(pad "173" smd rect
			(at 4.59994 23.800054 90)
			(size 1.8034 0.508)
			(layers "F.Cu" "F.Mask" "F.Paste")
			(net "GND")
		)
		(pad "174" smd rect
			(at 4.59994 24.649938 90)
			(size 1.8034 0.508)
			(layers "F.Cu" "F.Mask" "F.Paste")
			(net "M_B_DQS_DN<2>")
		)
		(pad "175" smd rect
			(at 4.59994 25.500076 90)
			(size 1.8034 0.508)
			(layers "F.Cu" "F.Mask" "F.Paste")
			(net "M_B_DQS_DP<2>")
		)
		(pad "176" smd rect
			(at 4.59994 26.34996 90)
			(size 1.8034 0.508)
			(layers "F.Cu" "F.Mask" "F.Paste")
			(net "GND")
		)
		(pad "177" smd rect
			(at 4.59994 27.200098 90)
			(size 1.8034 0.508)
			(layers "F.Cu" "F.Mask" "F.Paste")
			(net "M_B_DQ<22>")
		)
		(pad "178" smd rect
			(at 4.59994 28.049982 90)
			(size 1.8034 0.508)
			(layers "F.Cu" "F.Mask" "F.Paste")
			(net "GND")
		)
		(pad "179" smd rect
			(at 4.59994 28.90012 90)
			(size 1.8034 0.508)
			(layers "F.Cu" "F.Mask" "F.Paste")
			(net "M_B_DQ<18>")
		)
		(pad "180" smd rect
			(at 4.59994 29.750004 90)
			(size 1.8034 0.508)
			(layers "F.Cu" "F.Mask" "F.Paste")
			(net "GND")
		)
		(pad "181" smd rect
			(at 4.59994 30.599888 90)
			(size 1.8034 0.508)
			(layers "F.Cu" "F.Mask" "F.Paste")
			(net "M_B_DQ<28>")
		)
		(pad "182" smd rect
			(at 4.59994 31.450026 90)
			(size 1.8034 0.508)
			(layers "F.Cu" "F.Mask" "F.Paste")
			(net "GND")
		)
		(pad "183" smd rect
			(at 4.59994 32.29991 90)
			(size 1.8034 0.508)
			(layers "F.Cu" "F.Mask" "F.Paste")
			(net "M_B_DQ<24>")
		)
		(pad "184" smd rect
			(at 4.59994 33.150048 90)
			(size 1.8034 0.508)
			(layers "F.Cu" "F.Mask" "F.Paste")
			(net "GND")
		)
		(pad "185" smd rect
			(at 4.59994 33.999932 90)
			(size 1.8034 0.508)
			(layers "F.Cu" "F.Mask" "F.Paste")
			(net "M_B_DQS_DN<3>")
		)
		(pad "186" smd rect
			(at 4.59994 34.85007 90)
			(size 1.8034 0.508)
			(layers "F.Cu" "F.Mask" "F.Paste")
			(net "M_B_DQS_DP<3>")
		)
		(pad "187" smd rect
			(at 4.59994 35.699954 90)
			(size 1.8034 0.508)
			(layers "F.Cu" "F.Mask" "F.Paste")
			(net "GND")
		)
		(pad "188" smd rect
			(at 4.59994 36.550092 90)
			(size 1.8034 0.508)
			(layers "F.Cu" "F.Mask" "F.Paste")
			(net "M_B_DQ<30>")
		)
		(pad "189" smd rect
			(at 4.59994 37.399976 90)
			(size 1.8034 0.508)
			(layers "F.Cu" "F.Mask" "F.Paste")
			(net "GND")
		)
		(pad "190" smd rect
			(at 4.59994 38.250114 90)
			(size 1.8034 0.508)
			(layers "F.Cu" "F.Mask" "F.Paste")
			(net "M_B_DQ<26>")
		)
		(pad "191" smd rect
			(at 4.59994 39.099998 90)
			(size 1.8034 0.508)
			(layers "F.Cu" "F.Mask" "F.Paste")
			(net "GND")
		)
		(pad "192" smd rect
			(at 4.59994 39.949882 90)
			(size 1.8034 0.508)
			(layers "F.Cu" "F.Mask" "F.Paste")
			(net "M_B_ECC<4>")
		)
		(pad "193" smd rect
			(at 4.59994 40.80002 90)
			(size 1.8034 0.508)
			(layers "F.Cu" "F.Mask" "F.Paste")
			(net "GND")
		)
		(pad "194" smd rect
			(at 4.59994 41.649904 90)
			(size 1.8034 0.508)
			(layers "F.Cu" "F.Mask" "F.Paste")
			(net "M_B_ECC<0>")
		)
		(pad "195" smd rect
			(at 4.59994 42.500042 90)
			(size 1.8034 0.508)
			(layers "F.Cu" "F.Mask" "F.Paste")
			(net "GND")
		)
		(pad "196" smd rect
			(at 4.59994 43.349926 90)
			(size 1.8034 0.508)
			(layers "F.Cu" "F.Mask" "F.Paste")
			(net "M_B_DQS_DN<8>")
		)
		(pad "197" smd rect
			(at 4.59994 44.200064 90)
			(size 1.8034 0.508)
			(layers "F.Cu" "F.Mask" "F.Paste")
			(net "M_B_DQS_DP<8>")
		)
		(pad "198" smd rect
			(at 4.59994 45.049948 90)
			(size 1.8034 0.508)
			(layers "F.Cu" "F.Mask" "F.Paste")
			(net "GND")
		)
		(pad "199" smd rect
			(at 4.59994 45.900086 90)
			(size 1.8034 0.508)
			(layers "F.Cu" "F.Mask" "F.Paste")
			(net "M_B_ECC<6>")
		)
	)
)
